# BASEBOARD_FAB2 (Tioga Pass) — schematic netlist excerpt (pin names and nets, part order shuffled) for the footprints in the layout excerpt that follows; sources: Cadence DE-HDL packaged netlist, KiCad conversion of Wiwynn_Tioga_Pass_MB.brd

R6L3  RES  2 1.0% CHIP  pkg 0402  page 98 : A = M_F_CPU_VREF ; B = M_F_VREF
R1U38  RES  3.48K 1.0% CHIP  pkg 0402  page 169 : A = A_P3V3_STBY_SCALED ; B = GND
C8W2  CAP_A  0.1UF 16V 10% X7R  pkg 0402V  page 249 : A = P5V_STBY ; B = GND

(kicad_pcb
	(version 20260206)
	(generator "pcbnew")
	(generator_version "10.0")
	(general
		(thickness 1.6)
		(legacy_teardrops no)
	)
	(paper "A4")
	(title_block
		(title "Wiwynn_Tioga_Pass_MB.brd")
		(comment 1 "Tioga Pass / footprints 3258-3260 of 4770")
	)
	(layers
		(0 "F.Cu" signal "TOP")
		(4 "In1.Cu" signal "L2GND")
		(6 "In2.Cu" signal "L3")
		(8 "In3.Cu" signal "L4GND")
		(10 "In4.Cu" signal "L5")
		(12 "In5.Cu" signal "L6GND")
		(14 "In6.Cu" signal "L7VCC")
		(16 "In7.Cu" signal "L8VCC")
		(18 "In8.Cu" signal "L9GND")
		(20 "In9.Cu" signal "L10")
		(22 "In10.Cu" signal "L11GND")
		(24 "In11.Cu" signal "L12")
		(26 "In12.Cu" signal "L13GND")
		(2 "B.Cu" signal "BOTTOM")
		(9 "F.Adhes" user "F.Adhesive")
		(11 "B.Adhes" user "B.Adhesive")
		(13 "F.Paste" user "Package Geometry/Pastemask Top")
		(15 "B.Paste" user "Package Geometry/Pastemask Bottom")
		(5 "F.SilkS" user "Ref Des/Silkscreen Top")
		(7 "B.SilkS" user "Ref Des/Silkscreen Bottom")
		(1 "F.Mask" user "Board Geometry/Soldermask Top")
		(3 "B.Mask" user "Board Geometry/Soldermask Bottom")
		(17 "Dwgs.User" user "User.Drawings")
		(19 "Cmts.User" user "User.Comments")
		(21 "Eco1.User" user "User.Eco1")
		(23 "Eco2.User" user "User.Eco2")
		(25 "Edge.Cuts" user "Board Geometry/Outline")
		(27 "Margin" user)
		(31 "F.CrtYd" user "Package Geometry/Place Bound Top")
		(29 "B.CrtYd" user "Package Geometry/Place Bound Bottom")
		(35 "F.Fab" user "Ref Des/Assembly Top")
		(33 "B.Fab" user "Ref Des/Assembly Bottom")
	)
	(footprint ""
		(layer "B.Cu")
		(at 405.726646 -26.489152)
		(property "Reference" "R1U38"
			(at 0 0 0)
			(layer "B.SilkS")
			(hide yes)
			(effects
				(font
					(size 1.27 1.27)
				)
				(justify mirror)
			)
		)
		(property "Value" ""
			(at 0 0 0)
			(layer "B.Fab")
			(effects
				(font
					(size 1.27 1.27)
				)
				(justify mirror)
			)
		)
		(duplicate_pad_numbers_are_jumpers no)
		(fp_poly
			(pts
				(xy 0.2794 -0.1016) (xy -0.2794 -0.1016) (xy -0.2794 0.9906) (xy 0.2794 0.9906)
			)
			(stroke
				(width 0)
				(type default)
			)
			(fill no)
			(layer "B.CrtYd")
		)
		(fp_line
			(start -0.2794 -0.1016)
			(end 0.2794 -0.1016)
			(stroke
				(width 0.1)
				(type default)
			)
			(layer "B.Fab")
		)
		(fp_line
			(start -0.2794 0.9906)
			(end -0.2794 -0.1016)
			(stroke
				(width 0.1)
				(type default)
			)
			(layer "B.Fab")
		)
		(fp_line
			(start 0.2794 -0.1016)
			(end 0.2794 0.9906)
			(stroke
				(width 0.1)
				(type default)
			)
			(layer "B.Fab")
		)
		(fp_line
			(start 0.2794 0.9906)
			(end -0.2794 0.9906)
			(stroke
				(width 0.1)
				(type default)
			)
			(layer "B.Fab")
		)
		(pad "1" smd rect
			(at 0 0 180)
			(size 0.508 0.508)
			(layers "B.Cu" "B.Mask" "B.Paste")
			(net "A_P3V3_STBY_SCALED")
		)
		(pad "2" smd rect
			(at 0 0.889 180)
			(size 0.508 0.508)
			(layers "B.Cu" "B.Mask" "B.Paste")
			(net "GND")
		)
		(zone
			(layer "B.Cu")
			(hatch none 0.5)
			(connect_pads
				(clearance 0)
			)
			(min_thickness 0.25)
			(keepout
				(tracks allowed)
				(vias not_allowed)
				(pads allowed)
				(copperpour not_allowed)
				(footprints allowed)
			)
			(placement
				(enabled no)
				(sheetname "")
			)
			(fill
				(thermal_gap 0.5)
				(thermal_bridge_width 0.5)
				(island_removal_mode 0)
			)
			(polygon
				(pts
					(xy 405.980646 -26.235152) (xy 405.472646 -26.235152) (xy 405.472646 -25.854152) (xy 405.980646 -25.854152)
				)
			)
		)
		(zone
			(layer "B.Cu")
			(hatch none 0.5)
			(connect_pads
				(clearance 0)
			)
			(min_thickness 0.25)
			(keepout
				(tracks not_allowed)
				(vias allowed)
				(pads allowed)
				(copperpour not_allowed)
				(footprints allowed)
			)
			(placement
				(enabled no)
				(sheetname "")
			)
			(fill
				(thermal_gap 0.5)
				(thermal_bridge_width 0.5)
				(island_removal_mode 0)
			)
			(polygon
				(pts
					(xy 405.980646 -25.854152) (xy 405.472646 -25.854152) (xy 405.472646 -26.235152) (xy 405.980646 -26.235152)
				)
			)
		)
	)
	(footprint ""
		(layer "B.Cu")
		(at 192.786 -154.559 180)
		(property "Reference" "R6L3"
			(at 0 0 0)
			(layer "B.SilkS")
			(hide yes)
			(effects
				(font
					(size 1.27 1.27)
				)
				(justify mirror)
			)
		)
		(property "Value" ""
			(at 0 0 0)
			(layer "B.Fab")
			(effects
				(font
					(size 1.27 1.27)
				)
				(justify mirror)
			)
		)
		(duplicate_pad_numbers_are_jumpers no)
		(fp_poly
			(pts
				(xy 0.2794 -0.1016) (xy -0.2794 -0.1016) (xy -0.2794 0.9906) (xy 0.2794 0.9906)
			)
			(stroke
				(width 0)
				(type default)
			)
			(fill no)
			(layer "B.CrtYd")
		)
		(fp_line
			(start 0.2794 0.9906)
			(end -0.2794 0.9906)
			(stroke
				(width 0.1)
				(type default)
			)
			(layer "B.Fab")
		)
		(fp_line
			(start 0.2794 -0.1016)
			(end 0.2794 0.9906)
			(stroke
				(width 0.1)
				(type default)
			)
			(layer "B.Fab")
		)
		(fp_line
			(start -0.2794 0.9906)
			(end -0.2794 -0.1016)
			(stroke
				(width 0.1)
				(type default)
			)
			(layer "B.Fab")
		)
		(fp_line
			(start -0.2794 -0.1016)
			(end 0.2794 -0.1016)
			(stroke
				(width 0.1)
				(type default)
			)
			(layer "B.Fab")
		)
		(pad "1" smd rect
			(at 0 0)
			(size 0.508 0.508)
			(layers "B.Cu" "B.Mask" "B.Paste")
			(net "M_F_CPU_VREF")
		)
		(pad "2" smd rect
			(at 0 0.889)
			(size 0.508 0.508)
			(layers "B.Cu" "B.Mask" "B.Paste")
			(net "M_F_VREF")
		)
		(zone
			(layer "B.Cu")
			(hatch none 0.5)
			(connect_pads
				(clearance 0)
			)
			(min_thickness 0.25)
			(keepout
				(tracks not_allowed)
				(vias allowed)
				(pads allowed)
				(copperpour not_allowed)
				(footprints allowed)
			)
			(placement
				(enabled no)
				(sheetname "")
			)
			(fill
				(thermal_gap 0.5)
				(thermal_bridge_width 0.5)
				(island_removal_mode 0)
			)
			(polygon
				(pts
					(xy 192.532 -155.194) (xy 193.04 -155.194) (xy 193.04 -154.813) (xy 192.532 -154.813)
				)
			)
		)
		(zone
			(layer "B.Cu")
			(hatch none 0.5)
			(connect_pads
				(clearance 0)
			)
			(min_thickness 0.25)
			(keepout
				(tracks allowed)
				(vias not_allowed)
				(pads allowed)
				(copperpour not_allowed)
				(footprints allowed)
			)
			(placement
				(enabled no)
				(sheetname "")
			)
			(fill
				(thermal_gap 0.5)
				(thermal_bridge_width 0.5)
				(island_removal_mode 0)
			)
			(polygon
				(pts
					(xy 192.532 -154.813) (xy 193.04 -154.813) (xy 193.04 -155.194) (xy 192.532 -155.194)
				)
			)
		)
	)
	(footprint ""
		(layer "B.Cu")
		(at 444.45174 -20.85848 180)
		(property "Reference" "C8W2"
			(at 0.8382 -0.67818 180)
			(unlocked yes)
			(layer "B.SilkS")
			(effects
				(font
					(size 0.4064 0.254)
					(thickness 0.1524)
				)
				(justify left mirror)
			)
		)
		(property "Value" ""
			(at 0 0 0)
			(layer "B.Fab")
			(effects
				(font
					(size 1.27 1.27)
				)
				(justify mirror)
			)
		)
		(duplicate_pad_numbers_are_jumpers no)
		(fp_poly
			(pts
				(xy -0.3048 -0.1016) (xy -0.3048 0.9906) (xy 0.3048 0.9906) (xy 0.3048 -0.1016)
			)
			(stroke
				(width 0)
				(type default)
			)
			(fill no)
			(layer "B.CrtYd")
		)
		(fp_line
			(start 0.3048 0.9906)
			(end -0.3048 0.9906)
			(stroke
				(width 0.1)
				(type default)
			)
			(layer "B.Fab")
		)
		(fp_line
			(start 0.3048 -0.1016)
			(end 0.3048 0.9906)
			(stroke
				(width 0.1)
				(type default)
			)
			(layer "B.Fab")
		)
		(fp_line
			(start -0.3048 0.9906)
			(end -0.3048 -0.1016)
			(stroke
				(width 0.1)
				(type default)
			)
			(layer "B.Fab")
		)
		(fp_line
			(start -0.3048 -0.1016)
			(end 0.3048 -0.1016)
			(stroke
				(width 0.1)
				(type default)
			)
			(layer "B.Fab")
		)
		(pad "1" smd rect
			(at 0 0)
			(size 0.508 0.508)
			(layers "B.Cu" "B.Mask" "B.Paste")
			(net "P5V_STBY")
		)
		(pad "2" smd rect
			(at 0 0.889)
			(size 0.508 0.508)
			(layers "B.Cu" "B.Mask" "B.Paste")
			(net "GND")
		)
		(zone
			(layer "B.Cu")
			(hatch none 0.5)
			(connect_pads
				(clearance 0)
			)
			(min_thickness 0.25)
			(keepout
				(tracks not_allowed)
				(vias allowed)
				(pads allowed)
				(copperpour not_allowed)
				(footprints allowed)
			)
			(placement
				(enabled no)
				(sheetname "")
			)
			(fill
				(thermal_gap 0.5)
				(thermal_bridge_width 0.5)
				(island_removal_mode 0)
			)
			(polygon
				(pts
					(xy 444.19774 -21.49348) (xy 444.70574 -21.49348) (xy 444.70574 -21.11248) (xy 444.19774 -21.11248)
				)
			)
		)
		(zone
			(layer "B.Cu")
			(hatch none 0.5)
			(connect_pads
				(clearance 0)
			)
			(min_thickness 0.25)
			(keepout
				(tracks allowed)
				(vias not_allowed)
				(pads allowed)
				(copperpour not_allowed)
				(footprints allowed)
			)
			(placement
				(enabled no)
				(sheetname "")
			)
			(fill
				(thermal_gap 0.5)
				(thermal_bridge_width 0.5)
				(island_removal_mode 0)
			)
			(polygon
				(pts
					(xy 444.19774 -21.11248) (xy 444.70574 -21.11248) (xy 444.70574 -21.49348) (xy 444.19774 -21.49348)
				)
			)
		)
	)
)
